(kicad_pcb
	(version 20241229)
	(generator "pcbnew")
	(generator_version "9.0")
	(general
		(thickness 1.599998)
		(legacy_teardrops no)
	)
	(paper "A4")
	(title_block
		(title "Artix - Datacenter Secure Control Module (DC-SCM)")
		(date "2024-11-06")
		(rev "1.1.3")
		(comment 9 "footprints 94-98 of 544")
	)
	(layers
		(0 "F.Cu" signal)
		(4 "In1.Cu" signal)
		(6 "In2.Cu" signal)
		(8 "In3.Cu" signal)
		(10 "In4.Cu" signal)
		(12 "In5.Cu" signal)
		(14 "In6.Cu" signal)
		(2 "B.Cu" signal)
		(9 "F.Adhes" user "F.Adhesive")
		(11 "B.Adhes" user "B.Adhesive")
		(13 "F.Paste" user)
		(15 "B.Paste" user)
		(5 "F.SilkS" user "F.Silkscreen")
		(7 "B.SilkS" user "B.Silkscreen")
		(1 "F.Mask" user)
		(3 "B.Mask" user)
		(17 "Dwgs.User" user "User.Drawings")
		(19 "Cmts.User" user "User.Comments")
		(21 "Eco1.User" user "User.Eco1")
		(23 "Eco2.User" user "User.Eco2")
		(25 "Edge.Cuts" user)
		(27 "Margin" user)
		(31 "F.CrtYd" user "F.Courtyard")
		(29 "B.CrtYd" user "B.Courtyard")
		(35 "F.Fab" user)
		(33 "B.Fab" user)
	)
	(footprint "antmicro-footprints:PinSocket_2x6_P2.54mm_Drill1.02mm_PMOD"
		(layer "F.Cu")
		(at 65.13 103.05 90)
		(descr "http://portal.fciconnect.com/Comergent//fci/drawing/68020.pdf")
		(property "Reference" "J4"
			(at 2.7 -1.63 90)
			(layer "F.SilkS")
			(effects
				(font
					(size 0.7 0.7)
					(thickness 0.15)
				)
				(justify left bottom)
			)
		)
		(property "Value" "PinSocket_2x6_P2.54mm_Drill1.02mm_PMOD"
			(at 1.6 15.8 90)
			(layer "F.Fab")
			(effects
				(font
					(size 0.7 0.7)
					(thickness 0.15)
				)
				(justify left bottom)
			)
		)
		(property "Datasheet" "https://cdn.harwin.com/pdfs/M20-783.pdf"
			(at 0 0 90)
			(layer "F.Fab")
			(hide yes)
			(effects
				(font
					(size 1.27 1.27)
					(thickness 0.15)
				)
			)
		)
		(property "Description" "PCB Receptacle, Board-to-Board, 2.54 mm, 2 Rows, 12 Contacts, Through Hole Mount, M20"
			(at 0 0 90)
			(layer "F.Fab")
			(hide yes)
			(effects
				(font
					(size 1.27 1.27)
					(thickness 0.15)
				)
			)
		)
		(property "Author" "Antmicro"
			(at 168.18 37.92 0)
			(layer "F.Fab")
			(hide yes)
			(effects
				(font
					(size 1 1)
					(thickness 0.15)
				)
			)
		)
		(property "License" "Apache-2.0"
			(at 168.18 37.92 0)
			(layer "F.Fab")
			(hide yes)
			(effects
				(font
					(size 1 1)
					(thickness 0.15)
				)
			)
		)
		(property "MPN" "M20-7830642"
			(at 168.18 37.92 0)
			(layer "F.Fab")
			(hide yes)
			(effects
				(font
					(size 1 1)
					(thickness 0.15)
				)
			)
		)
		(property "Manufacturer" "Harwin"
			(at 168.18 37.92 0)
			(layer "F.Fab")
			(hide yes)
			(effects
				(font
					(size 1 1)
					(thickness 0.15)
				)
			)
		)
		(sheetname "/RoT/")
		(sheetfile "rot.kicad_sch")
		(attr through_hole)
		(fp_line
			(start 3.898 -1.401)
			(end 3.499 -1.401)
			(stroke
				(width 0.15)
				(type solid)
			)
			(layer "F.SilkS")
		)
		(fp_line
			(start 3.898 -1.401)
			(end 3.898 -1)
			(stroke
				(width 0.15)
				(type solid)
			)
			(layer "F.SilkS")
		)
		(fp_line
			(start -1.401 -1.401)
			(end -1 -1.401)
			(stroke
				(width 0.15)
				(type solid)
			)
			(layer "F.SilkS")
		)
		(fp_line
			(start -1.401 -1.401)
			(end -1.401 -1)
			(stroke
				(width 0.15)
				(type solid)
			)
			(layer "F.SilkS")
		)
		(fp_line
			(start 3.898 14.098)
			(end 3.898 13.698)
			(stroke
				(width 0.15)
				(type solid)
			)
			(layer "F.SilkS")
		)
		(fp_line
			(start 3.898 14.098)
			(end 3.499 14.098)
			(stroke
				(width 0.15)
				(type solid)
			)
			(layer "F.SilkS")
		)
		(fp_line
			(start -1.401 14.098)
			(end -1.401 13.698)
			(stroke
				(width 0.15)
				(type solid)
			)
			(layer "F.SilkS")
		)
		(fp_line
			(start -1.401 14.098)
			(end -1 14.098)
			(stroke
				(width 0.15)
				(type solid)
			)
			(layer "F.SilkS")
		)
		(fp_line
			(start -1.52 -1.52)
			(end 4.04 -1.52)
			(stroke
				(width 0.05)
				(type solid)
			)
			(layer "F.CrtYd")
		)
		(fp_line
			(start 4.04 14.22)
			(end 4.04 -1.52)
			(stroke
				(width 0.05)
				(type solid)
			)
			(layer "F.CrtYd")
		)
		(fp_line
			(start -1.52 14.22)
			(end -1.52 -1.52)
			(stroke
				(width 0.05)
				(type solid)
			)
			(layer "F.CrtYd")
		)
		(fp_line
			(start -1.52 14.22)
			(end 4.04 14.22)
			(stroke
				(width 0.05)
				(type solid)
			)
			(layer "F.CrtYd")
		)
		(fp_line
			(start 3.809 -1.27)
			(end 3.809 13.97)
			(stroke
				(width 0.15)
				(type solid)
			)
			(layer "F.Fab")
		)
		(fp_line
			(start -1.27 -1.27)
			(end 3.809 -1.27)
			(stroke
				(width 0.15)
				(type solid)
			)
			(layer "F.Fab")
		)
		(fp_line
			(start -1.27 -1.27)
			(end -1.27 13.97)
			(stroke
				(width 0.15)
				(type solid)
			)
			(layer "F.Fab")
		)
		(fp_line
			(start -1.27 13.97)
			(end 3.809 13.97)
			(stroke
				(width 0.15)
				(type solid)
			)
			(layer "F.Fab")
		)
		(pad "1" thru_hole circle
			(at 0 0 90)
			(size 1.8 1.8)
			(drill 1.02)
			(layers "*.Cu" "*.Mask")
			(remove_unused_layers no)
			(net 55 "SPI0_CS_N")
			(pintype "passive")
		)
		(pad "2" thru_hole circle
			(at 0 2.539 90)
			(size 1.8 1.8)
			(drill 1.02)
			(layers "*.Cu" "*.Mask")
			(remove_unused_layers no)
			(net 57 "SPI0_MOSI")
			(pintype "passive")
		)
		(pad "3" thru_hole circle
			(at 0 5.078 90)
			(size 1.8 1.8)
			(drill 1.02)
			(layers "*.Cu" "*.Mask")
			(remove_unused_layers no)
			(net 58 "SPI0_MISO")
			(pintype "passive")
		)
		(pad "4" thru_hole circle
			(at 0 7.618 90)
			(size 1.8 1.8)
			(drill 1.02)
			(layers "*.Cu" "*.Mask")
			(remove_unused_layers no)
			(net 56 "SPI0_CLK")
			(pintype "passive")
		)
		(pad "5" thru_hole circle
			(at 0 10.159 90)
			(size 1.8 1.8)
			(drill 1.02)
			(layers "*.Cu" "*.Mask")
			(remove_unused_layers no)
			(net 1 "GND")
			(pintype "passive")
		)
		(pad "6" thru_hole circle
			(at 0 12.698 90)
			(size 1.8 1.8)
			(drill 1.02)
			(layers "*.Cu" "*.Mask")
			(remove_unused_layers no)
			(net 2 "VCC3V3")
			(pintype "passive")
		)
		(pad "7" thru_hole circle
			(at 2.539 0 90)
			(size 1.8 1.8)
			(drill 1.02)
			(layers "*.Cu" "*.Mask")
			(remove_unused_layers no)
			(net 592 "TPM_PIRQ#")
			(pintype "passive")
		)
		(pad "8" thru_hole circle
			(at 2.539 2.539 90)
			(size 1.8 1.8)
			(drill 1.02)
			(layers "*.Cu" "*.Mask")
			(remove_unused_layers no)
			(net 591 "TPM_RST")
			(pintype "passive")
		)
		(pad "9" thru_hole circle
			(at 2.539 5.078 90)
			(size 1.8 1.8)
			(drill 1.02)
			(layers "*.Cu" "*.Mask")
			(remove_unused_layers no)
			(net 590 "TPM_GPIO")
			(pintype "passive")
		)
		(pad "10" thru_hole circle
			(at 2.539 7.618 90)
			(size 1.8 1.8)
			(drill 1.02)
			(layers "*.Cu" "*.Mask")
			(remove_unused_layers no)
			(net 589 "TPM_PP")
			(pintype "passive")
		)
		(pad "11" thru_hole circle
			(at 2.539 10.159 90)
			(size 1.8 1.8)
			(drill 1.02)
			(layers "*.Cu" "*.Mask")
			(remove_unused_layers no)
			(net 1 "GND")
			(pintype "passive")
		)
		(pad "12" thru_hole circle
			(at 2.539 12.698 90)
			(size 1.8 1.8)
			(drill 1.02)
			(layers "*.Cu" "*.Mask")
			(remove_unused_layers no)
			(net 2 "VCC3V3")
			(pintype "passive")
		)
	)
	(footprint "antmicro-footprints:R_0402_1005Metric"
		(layer "F.Cu")
		(at 124.57 154.22 -90)
		(descr "Resistor SMD 0402")
		(tags "resistor SMD 0402")
		(property "Reference" "R20"
			(at -2.92 -0.33 90)
			(layer "F.SilkS")
			(effects
				(font
					(size 0.7 0.7)
					(thickness 0.15)
				)
				(justify right bottom)
			)
		)
		(property "Value" "R_10k_0402"
			(at 0 1.4 90)
			(layer "F.Fab")
			(effects
				(font
					(size 0.7 0.7)
					(thickness 0.15)
				)
				(justify right bottom)
			)
		)
		(property "Datasheet" "https://www.bourns.com/docs/product-datasheets/cr.pdf"
			(at 0 0 270)
			(layer "F.Fab")
			(hide yes)
			(effects
				(font
					(size 1.27 1.27)
					(thickness 0.15)
				)
			)
		)
		(property "Description" "SMD Chip Resistor, 10 kohm, ± 1%, 62.5 mW, 0402 [1005 Metric], Thick Film, General Purpose"
			(at 0 0 270)
			(layer "F.Fab")
			(hide yes)
			(effects
				(font
					(size 1.27 1.27)
					(thickness 0.15)
				)
			)
		)
		(property "Author" "Antmicro"
			(at -29.65 278.79 0)
			(layer "F.Fab")
			(hide yes)
			(effects
				(font
					(size 1 1)
					(thickness 0.15)
				)
			)
		)
		(property "License" "Apache-2.0"
			(at -29.65 278.79 0)
			(layer "F.Fab")
			(hide yes)
			(effects
				(font
					(size 1 1)
					(thickness 0.15)
				)
			)
		)
		(property "MPN" "CR0402-FX-1002GLF"
			(at -29.65 278.79 0)
			(layer "F.Fab")
			(hide yes)
			(effects
				(font
					(size 1 1)
					(thickness 0.15)
				)
			)
		)
		(property "Manufacturer" "Bourns"
			(at -29.65 278.79 0)
			(layer "F.Fab")
			(hide yes)
			(effects
				(font
					(size 1 1)
					(thickness 0.15)
				)
			)
		)
		(property "Tolerance" "1%"
			(at -29.65 278.79 0)
			(layer "F.Fab")
			(hide yes)
			(effects
				(font
					(size 1 1)
					(thickness 0.15)
				)
			)
		)
		(property "Val" "10k"
			(at -29.65 278.79 0)
			(layer "F.Fab")
			(hide yes)
			(effects
				(font
					(size 1 1)
					(thickness 0.15)
				)
			)
		)
		(sheetname "/PCIe-connector/")
		(sheetfile "pcie-conn.kicad_sch")
		(attr smd)
		(fp_rect
			(start -0.925 -0.47)
			(end 0.925 0.47)
			(stroke
				(width 0.05)
				(type default)
			)
			(fill no)
			(layer "F.CrtYd")
		)
		(fp_rect
			(start -0.5 -0.25)
			(end 0.5 0.25)
			(stroke
				(width 0.15)
				(type solid)
			)
			(fill no)
			(layer "F.Fab")
		)
		(pad "1" smd roundrect
			(at -0.48 0 270)
			(size 0.59 0.64)
			(layers "F.Cu" "F.Mask" "F.Paste")
			(roundrect_rratio 0.25)
			(net 5 "VCC1V8")
			(pintype "passive")
		)
		(pad "2" smd roundrect
			(at 0.48 0 270)
			(size 0.59 0.64)
			(layers "F.Cu" "F.Mask" "F.Paste")
			(roundrect_rratio 0.25)
			(net 264 "Net-(J2-ALERT)")
			(pintype "passive")
		)
	)
	(footprint "antmicro-footprints:R_0402_1005Metric"
		(layer "F.Cu")
		(at 129.975 115.675 180)
		(descr "Resistor SMD 0402")
		(tags "resistor SMD 0402")
		(property "Reference" "R5"
			(at 0.775 -0.425 0)
			(layer "F.SilkS")
			(effects
				(font
					(size 0.7 0.7)
					(thickness 0.15)
				)
				(justify right bottom)
			)
		)
		(property "Value" "R_12k_0402"
			(at 0 1.4 0)
			(layer "F.Fab")
			(effects
				(font
					(size 0.7 0.7)
					(thickness 0.15)
				)
				(justify right bottom)
			)
		)
		(property "Datasheet" "https://www.bourns.com/docs/product-datasheets/cr.pdf"
			(at 0 0 180)
			(layer "F.Fab")
			(hide yes)
			(effects
				(font
					(size 1.27 1.27)
					(thickness 0.15)
				)
			)
		)
		(property "Description" "SMD Chip Resistor, 12 kohm, ± 1%, 62.5 mW, 0402 [1005 Metric], Thick Film, General Purpose"
			(at 0 0 180)
			(layer "F.Fab")
			(hide yes)
			(effects
				(font
					(size 1.27 1.27)
					(thickness 0.15)
				)
			)
		)
		(property "Author" "Antmicro"
			(at 259.95 231.35 0)
			(layer "F.Fab")
			(hide yes)
			(effects
				(font
					(size 1 1)
					(thickness 0.15)
				)
			)
		)
		(property "License" "Apache-2.0"
			(at 259.95 231.35 0)
			(layer "F.Fab")
			(hide yes)
			(effects
				(font
					(size 1 1)
					(thickness 0.15)
				)
			)
		)
		(property "MPN" "CR0402-FX-1202GLF"
			(at 259.95 231.35 0)
			(layer "F.Fab")
			(hide yes)
			(effects
				(font
					(size 1 1)
					(thickness 0.15)
				)
			)
		)
		(property "Manufacturer" "Bourns"
			(at 259.95 231.35 0)
			(layer "F.Fab")
			(hide yes)
			(effects
				(font
					(size 1 1)
					(thickness 0.15)
				)
			)
		)
		(property "Tolerance" "1%"
			(at 259.95 231.35 0)
			(layer "F.Fab")
			(hide yes)
			(effects
				(font
					(size 1 1)
					(thickness 0.15)
				)
			)
		)
		(property "Val" "12k"
			(at 259.95 231.35 0)
			(layer "F.Fab")
			(hide yes)
			(effects
				(font
					(size 1 1)
					(thickness 0.15)
				)
			)
		)
		(sheetname "/Interfaces/")
		(sheetfile "interfaces.kicad_sch")
		(attr smd)
		(fp_rect
			(start -0.925 -0.47)
			(end 0.925 0.47)
			(stroke
				(width 0.05)
				(type default)
			)
			(fill no)
			(layer "F.CrtYd")
		)
		(fp_rect
			(start -0.5 -0.25)
			(end 0.5 0.25)
			(stroke
				(width 0.15)
				(type solid)
			)
			(fill no)
			(layer "F.Fab")
		)
		(pad "1" smd roundrect
			(at -0.48 0 180)
			(size 0.59 0.64)
			(layers "F.Cu" "F.Mask" "F.Paste")
			(roundrect_rratio 0.25)
			(net 1 "GND")
			(pintype "passive")
		)
		(pad "2" smd roundrect
			(at 0.48 0 180)
			(size 0.59 0.64)
			(layers "F.Cu" "F.Mask" "F.Paste")
			(roundrect_rratio 0.25)
			(net 300 "Net-(U17-RBIAS)")
			(pintype "passive")
		)
	)
	(footprint "antmicro-footprints:R_0402_1005Metric"
		(layer "F.Cu")
		(at 128.575 131.375 180)
		(descr "Resistor SMD 0402")
		(tags "resistor SMD 0402")
		(property "Reference" "R7"
			(at -2.225 -0.325 0)
			(layer "F.SilkS")
			(effects
				(font
					(size 0.7 0.7)
					(thickness 0.15)
				)
				(justify right bottom)
			)
		)
		(property "Value" "R_12k_0402"
			(at 0 1.4 0)
			(layer "F.Fab")
			(effects
				(font
					(size 0.7 0.7)
					(thickness 0.15)
				)
				(justify right bottom)
			)
		)
		(property "Datasheet" "https://www.bourns.com/docs/product-datasheets/cr.pdf"
			(at 0 0 180)
			(layer "F.Fab")
			(hide yes)
			(effects
				(font
					(size 1.27 1.27)
					(thickness 0.15)
				)
			)
		)
		(property "Description" "SMD Chip Resistor, 12 kohm, ± 1%, 62.5 mW, 0402 [1005 Metric], Thick Film, General Purpose"
			(at 0 0 180)
			(layer "F.Fab")
			(hide yes)
			(effects
				(font
					(size 1.27 1.27)
					(thickness 0.15)
				)
			)
		)
		(property "Author" "Antmicro"
			(at 257.15 262.75 0)
			(layer "F.Fab")
			(hide yes)
			(effects
				(font
					(size 1 1)
					(thickness 0.15)
				)
			)
		)
		(property "License" "Apache-2.0"
			(at 257.15 262.75 0)
			(layer "F.Fab")
			(hide yes)
			(effects
				(font
					(size 1 1)
					(thickness 0.15)
				)
			)
		)
		(property "MPN" "CR0402-FX-1202GLF"
			(at 257.15 262.75 0)
			(layer "F.Fab")
			(hide yes)
			(effects
				(font
					(size 1 1)
					(thickness 0.15)
				)
			)
		)
		(property "Manufacturer" "Bourns"
			(at 257.15 262.75 0)
			(layer "F.Fab")
			(hide yes)
			(effects
				(font
					(size 1 1)
					(thickness 0.15)
				)
			)
		)
		(property "Tolerance" "1%"
			(at 257.15 262.75 0)
			(layer "F.Fab")
			(hide yes)
			(effects
				(font
					(size 1 1)
					(thickness 0.15)
				)
			)
		)
		(property "Val" "12k"
			(at 257.15 262.75 0)
			(layer "F.Fab")
			(hide yes)
			(effects
				(font
					(size 1 1)
					(thickness 0.15)
				)
			)
		)
		(sheetname "/Interfaces/")
		(sheetfile "interfaces.kicad_sch")
		(attr smd)
		(fp_rect
			(start -0.925 -0.47)
			(end 0.925 0.47)
			(stroke
				(width 0.05)
				(type default)
			)
			(fill no)
			(layer "F.CrtYd")
		)
		(fp_rect
			(start -0.5 -0.25)
			(end 0.5 0.25)
			(stroke
				(width 0.15)
				(type solid)
			)
			(fill no)
			(layer "F.Fab")
		)
		(pad "1" smd roundrect
			(at -0.48 0 180)
			(size 0.59 0.64)
			(layers "F.Cu" "F.Mask" "F.Paste")
			(roundrect_rratio 0.25)
			(net 1 "GND")
			(pintype "passive")
		)
		(pad "2" smd roundrect
			(at 0.48 0 180)
			(size 0.59 0.64)
			(layers "F.Cu" "F.Mask" "F.Paste")
			(roundrect_rratio 0.25)
			(net 303 "Net-(U18-RBIAS)")
			(pintype "passive")
		)
	)
	(footprint "antmicro-footprints:R_0402_1005Metric"
		(layer "F.Cu")
		(at 129.975 116.775 180)
		(descr "Resistor SMD 0402")
		(tags "resistor SMD 0402")
		(property "Reference" "R10"
			(at 0.775 -0.425 0)
			(layer "F.SilkS")
			(effects
				(font
					(size 0.7 0.7)
					(thickness 0.15)
				)
				(justify right bottom)
			)
		)
		(property "Value" "R_0R_0402"
			(at 0 1.4 0)
			(layer "F.Fab")
			(effects
				(font
					(size 0.7 0.7)
					(thickness 0.15)
				)
				(justify right bottom)
			)
		)
		(property "Datasheet" "https://industrial.panasonic.com/cdbs/www-data/pdf/RDA0000/AOA0000C301.pdf"
			(at 0 0 180)
			(layer "F.Fab")
			(hide yes)
			(effects
				(font
					(size 1.27 1.27)
					(thickness 0.15)
				)
			)
		)
		(property "Description" "SMD Chip Resistor, Jumper, 0 ohm, 100 mW, 0402 [1005 Metric], Thick Film, General Purpose"
			(at 0 0 180)
			(layer "F.Fab")
			(hide yes)
			(effects
				(font
					(size 1.27 1.27)
					(thickness 0.15)
				)
			)
		)
		(property "Author" "Antmicro"
			(at 259.95 233.55 0)
			(layer "F.Fab")
			(hide yes)
			(effects
				(font
					(size 1 1)
					(thickness 0.15)
				)
			)
		)
		(property "Current" "1A"
			(at 259.95 233.55 0)
			(layer "F.Fab")
			(hide yes)
			(effects
				(font
					(size 1 1)
					(thickness 0.15)
				)
			)
		)
		(property "License" "Apache-2.0"
			(at 259.95 233.55 0)
			(layer "F.Fab")
			(hide yes)
			(effects
				(font
					(size 1 1)
					(thickness 0.15)
				)
			)
		)
		(property "MPN" "ERJ2GE0R00X"
			(at 259.95 233.55 0)
			(layer "F.Fab")
			(hide yes)
			(effects
				(font
					(size 1 1)
					(thickness 0.15)
				)
			)
		)
		(property "Manufacturer" "Panasonic"
			(at 259.95 233.55 0)
			(layer "F.Fab")
			(hide yes)
			(effects
				(font
					(size 1 1)
					(thickness 0.15)
				)
			)
		)
		(property "Tolerance" "~"
			(at 259.95 233.55 0)
			(layer "F.Fab")
			(hide yes)
			(effects
				(font
					(size 1 1)
					(thickness 0.15)
				)
			)
		)
		(property "Val" "0R"
			(at 259.95 233.55 0)
			(layer "F.Fab")
			(hide yes)
			(effects
				(font
					(size 1 1)
					(thickness 0.15)
				)
			)
		)
		(sheetname "/Interfaces/")
		(sheetfile "interfaces.kicad_sch")
		(attr smd)
		(fp_rect
			(start -0.925 -0.47)
			(end 0.925 0.47)
			(stroke
				(width 0.05)
				(type default)
			)
			(fill no)
			(layer "F.CrtYd")
		)
		(fp_rect
			(start -0.5 -0.25)
			(end 0.5 0.25)
			(stroke
				(width 0.15)
				(type solid)
			)
			(fill no)
			(layer "F.Fab")
		)
		(pad "1" smd roundrect
			(at -0.48 0 180)
			(size 0.59 0.64)
			(layers "F.Cu" "F.Mask" "F.Paste")
			(roundrect_rratio 0.25)
			(net 2 "VCC3V3")
			(pintype "passive")
		)
		(pad "2" smd roundrect
			(at 0.48 0 180)
			(size 0.59 0.64)
			(layers "F.Cu" "F.Mask" "F.Paste")
			(roundrect_rratio 0.25)
			(net 308 "Net-(U17-REG_EN)")
			(pintype "passive")
		)
	)
)
